# BASEBOARD_FAB2 (Tioga Pass) — schematic parts with pin connectivity, parts 4665–4665 of 4751; source: Cadence DE-HDL packaged netlist (pstxprt.dat, pstxnet.dat, pstchip.dat)

U5D1  SKX_EXT_B  IC  pkg BGA1  page 21  (pins 1357-1695 of 3647)
  CC18  VSS(507)  GROUND  = GND
  CC20  RSVD(112)  BI  = PVCCMCP_CPU0
  CC22  CD_TDO  OUT  = JTAG_MCP_CPU0_TDO
  CC24  VSS(506)  GROUND  = GND
  CC26  VCCIO(83)  POWER  = PVCCIO_CPU0
  CC60  VCCIN(44)  POWER  = PVCCIN_CPU0
  CC62  VCCIN(43)  POWER  = PVCCIN_CPU0
  CC64  VSS(505)  GROUND  = GND
  CC66  VCCSA(22)  POWER  = PVSA_CPU0
  CC68  VCCSA(21)  POWER  = PVSA_CPU0
  CC70  VCCSA(20)  POWER  = PVSA_CPU0
  CC72  VSS(504)  GROUND  = GND
  CC74  VSS(503)  GROUND  = GND
  CC76  VSS(502)  GROUND  = GND
  CC78  VSS(501)  GROUND  = GND
  CC80  VSS(500)  GROUND  = GND
  CC82  VSS(499)  GROUND  = GND
  CC84  VCCIN(42)  POWER  = PVCCIN_CPU0
  CD3  PE2_TX_DP(8)  OUT  = P3E_CPU0_PE2_SS_TXP<8>
  CD5  VSS(498)  GROUND  = GND
  CD7  PE2_RX_DP(6)  IN  = P3E_CPU0_PE2_SS_RXP<6>
  CD9  VCCIO(27)  POWER  = PVCCIO_CPU0
  CD11  UPI2_TX_DP(17)  OUT  = TP_CPU0_UPI2_RSVD_DK19
  CD13  VSS(497)  GROUND  = GND
  CD15  UPI2_RX_DN(16)  IN  = GND
  CD17  UPI2_RX_DP(17)  IN  = GND
  CD19  RSVD(110)  BI  = PVCCMCP_CPU0
  CD21  RSVD(109)  BI  = PVCCMCP_CPU0
  CD23  CD_TRST_N  IN  = JTAG_MCP_TRST_N
  CD25  RSVD(108)  BI  = TP_CPU0_RSVD_108
  CD27  VCCIO(82)  POWER  = PVCCIO_CPU0
  CD61  VCCIN(41)  POWER  = PVCCIN_CPU0
  CD63  VSS(496)  GROUND  = GND
  CD65  VCCSA(19)  POWER  = PVSA_CPU0
  CD67  VCCSA(18)  POWER  = PVSA_CPU0
  CD69  VCCSA(17)  POWER  = PVSA_CPU0
  CD71  VCCSA(16)  POWER  = PVSA_CPU0
  CD73  VSS(495)  GROUND  = GND
  CD75  VSS(494)  GROUND  = GND
  CD77  VSS(493)  GROUND  = GND
  CD79  VSS(492)  GROUND  = GND
  CD81  VSS(491)  GROUND  = GND
  CD83  VCCIN(40)  POWER  = PVCCIN_CPU0
  CD85  VCCIN(39)  POWER  = PVCCIN_CPU0
  CE2  PE2_TX_DP(6)  OUT  = P3E_CPU0_PE2_SS_TXP<6>
  CE4  PE2_TX_DP(7)  OUT  = P3E_CPU0_PE2_SS_TXP<7>
  CE6  PE2_RX_DN(6)  IN  = P3E_CPU0_PE2_SS_RXN<6>
  CE8  PE2_RX_DN(7)  IN  = P3E_CPU0_PE2_SS_RXN<7>
  CE10  VSS(490)  GROUND  = GND
  CE12  UPI2_TX_DN(17)  OUT  = TP_CPU0_UPI2_RSVD_DL20
  CE14  VSS(489)  GROUND  = GND
  CE16  UPI2_RX_DN(15)  IN  = GND
  CE18  VCCIO(26)  POWER  = PVCCIO_CPU0
  CE20  VSS(488)  GROUND  = GND
  CE22  RSVD(107)  BI  = PVCCMCP_CPU0
  CE24  CD_TMS  IN  = JTAG_MCP_TMS
  CE26  VSS(487)  GROUND  = GND
  CE60  VCCIN(38)  POWER  = PVCCIN_CPU0
  CE62  VSS(486)  GROUND  = GND
  CE64  VCCSA(15)  POWER  = PVSA_CPU0
  CE66  VCCSA(14)  POWER  = PVSA_CPU0
  CE68  VCCSA(13)  POWER  = PVSA_CPU0
  CE70  VSS(485)  GROUND  = GND
  CE72  VCCSA(12)  POWER  = PVSA_CPU0
  CE74  VCCSA(11)  POWER  = PVSA_CPU0
  CE76  VCCSA_SENSE  POWER  = VSENSE_PVSA_CPU0_SKT_VSEN
  CE78  RSVD(106)  BI  = TP_CPU0_RSVD_106
  CE80  RSVD(105)  BI  = TP_CPU0_RSVD_105
  CE82  VSS(484)  GROUND  = GND
  CE84  VCCIN(37)  POWER  = PVCCIN_CPU0
  CF3  PE2_TX_DN(7)  OUT  = P3E_CPU0_PE2_SS_TXN<7>
  CF5  VCCIO(9)  POWER  = PVCCIO_CPU0
  CF7  PE2_RX_DP(5)  IN  = P3E_CPU0_PE2_SS_RXP<5>
  CF9  VSS(482)  GROUND  = GND
  CF11  UPI2_TX_DP(16)  OUT  = TP_CPU0_UPI2_RSVD_DJ20
  CF13  UPI2_TX_DN(15)  OUT  = TP_CPU0_UPI2_RSVD_DH19
  CF15  UPI2_RX_DP(15)  IN  = GND
  CF17  UPI2_RX_DN(17)  IN  = GND
  CF19  RSVD(104)  BI  = PVCCMCP_CPU0
  CF21  RSVD(103)  BI  = PVCCMCP_CPU0
  CF23  RSVD(102)  BI  = PVCCMCP_CPU0
  CF25  CD_POR_N  BI  = RST_CD_CPU0_POR_N
  CF27  VCCIO(81)  POWER  = PVCCIO_CPU0
  CF61  VCCIN(36)  POWER  = PVCCIN_CPU0
  CF63  VSS(481)  GROUND  = GND
  CF65  VCCSA(10)  POWER  = PVSA_CPU0
  CF67  VCCSA(9)  POWER  = PVSA_CPU0
  CF69  VSS(480)  GROUND  = GND
  CF71  VSS(479)  GROUND  = GND
  CF73  VCCSA(8)  POWER  = PVSA_CPU0
  CF75  VCCSA(7)  POWER  = PVSA_CPU0
  CF77  VSS(478)  GROUND  = GND
  CF79  RSVD(101)  BI  = TP_CPU0_RSVD_101
  CF81  RSVD(100)  BI  = TP_CPU0_RSVD_100
  CF83  VSS(477)  GROUND  = GND
  CF85  VCCIN(35)  POWER  = PVCCIN_CPU0
  CG2  PE2_TX_DN(6)  OUT  = P3E_CPU0_PE2_SS_TXN<6>
  CG4  DMI_TX_DN(0)  OUT  = DMI_CPU0_PCH_TX_DN<0>
  CG6  VSS(1191)  GROUND  = GND
  CG8  PE2_RX_DN(5)  IN  = P3E_CPU0_PE2_SS_RXN<5>
  CG10  RSVD(99)  BI  = TP_CPU0_RSVD_99
  CG12  UPI2_TX_DP(15)  OUT  = TP_CPU0_UPI2_RSVD_DJ18
  CG14  VCCIO(10)  POWER  = PVCCIO_CPU0
  CG16  UPI2_RX_DP(14)  IN  = GND
  CG18  VSS(475)  GROUND  = GND
  CG20  RSVD(98)  BI  = PVCCMCP_CPU0
  CG22  VSS(474)  GROUND  = GND
  CG24  RSVD(97)  BI  = TP_CPU0_RSVD_97
  CG26  RSVD(96)  BI  = PVCCMCP_CPU0
  CG60  VCCIN(34)  POWER  = PVCCIN_CPU0
  CG62  VSS(473)  GROUND  = GND
  CG64  VCCSA(6)  POWER  = PVSA_CPU0
  CG66  VCCSA(5)  POWER  = PVSA_CPU0
  CG68  VSS(472)  GROUND  = GND
  CG70  DDR5_DQS_DP(17)  BI  = M_F_DQS_DP<17>
  CG72  VSS(471)  GROUND  = GND
  CG74  VCCSA(4)  POWER  = PVSA_CPU0
  CG76  VSS_VCCSA_SENSE  POWER  = VSENSE_PVSA_CPU0_SKT_VRTN
  CG78  RSVD(95)  BI  = TP_CPU0_RSVD_95
  CG80  VSS(470)  GROUND  = GND
  CG82  RSVD(94)  BI  = TP_CPU0_RSVD_94
  CG84  VCCIN(33)  POWER  = PVCCIN_CPU0
  CH1  VSS(469)  GROUND  = GND
  CH3  VSS(468)  GROUND  = GND
  CH5  DMI_TX_DP(0)  OUT  = DMI_CPU0_PCH_TX_DP<0>
  CH7  PE2_RX_DP(4)  IN  = P3E_CPU0_PE2_SS_RXP<4>
  CH9  VCCIO(24)  POWER  = PVCCIO_CPU0
  CH11  UPI2_TX_DN(16)  OUT  = TP_CPU0_UPI2_RSVD_DG20
  CH13  UPI2_TX_DP(14)  OUT  = TP_CPU0_UPI2_RSVD_DH17
  CH15  VSS(467)  GROUND  = GND
  CH17  UPI2_RX_DN(14)  IN  = GND
  CH19  VSS(466)  GROUND  = GND
  CH21  RSVD(93)  BI  = PVCCMCP_CPU0
  CH23  RSVD(92)  BI  = PVCCMCP_CPU0
  CH25  RSVD(91)  BI  = TP_CPU0_RSVD_91
  CH27  VCCIO(85)  POWER  = PVCCIO_CPU0
  CH61  VCCIN(32)  POWER  = PVCCIN_CPU0
  CH63  VSS(465)  GROUND  = GND
  CH65  VCCSA(3)  POWER  = PVSA_CPU0
  CH67  VSS(464)  GROUND  = GND
  CH69  DDR5_ECC(6)  BI  = M_F_ECC<6>
  CH71  DDR5_ECC(0)  BI  = M_F_ECC<0>
  CH73  VSS(463)  GROUND  = GND
  CH75  VCCSA(2)  POWER  = PVSA_CPU0
  CH77  RSVD(90)  BI  = TP_CPU0_RSVD_90
  CH79  VSS(462)  GROUND  = GND
  CH81  VSS(461)  GROUND  = GND
  CH83  VSS(460)  GROUND  = GND
  CH85  VCCIN(31)  POWER  = PVCCIN_CPU0
  CJ2  VSS(459)  GROUND  = GND
  CJ4  DMI_TX_DN(1)  OUT  = DMI_CPU0_PCH_TX_DN<1>
  CJ6  VSS(458)  GROUND  = GND
  CJ8  VSS(457)  GROUND  = GND
  CJ10  VSS(456)  GROUND  = GND
  CJ12  VSS(455)  GROUND  = GND
  CJ14  UPI2_TX_DN(14)  OUT  = TP_CPU0_UPI2_RSVD_DK17
  CJ16  UPI2_RX_DP(12)  IN  = GND
  CJ18  UPI2_RX_DN(13)  IN  = GND
  CJ20  RSVD(89)  BI  = PVCCMCP_CPU0
  CJ22  RSVD(88)  BI  = PVCCMCP_CPU0
  CJ24  RSVD(87)  BI  = PVCCMCP_CPU0
  CJ26  RSVD(86)  BI  = PVCCMCP_CPU0
  CJ28  VCCIO(84)  POWER  = PVCCIO_CPU0
  CJ60  VCCIN(30)  POWER  = PVCCIN_CPU0
  CJ62  VSS(452)  GROUND  = GND
  CJ64  VCCSA(1)  POWER  = PVSA_CPU0
  CJ66  VCCSA(0)  POWER  = PVSA_CPU0
  CJ68  DDR5_ECC(2)  BI  = M_F_ECC<2>
  CJ70  DDR5_DQS_DN(17)  BI  = M_F_DQS_DN<17>
  CJ72  DDR5_ECC(4)  BI  = M_F_ECC<4>
  CJ74  VSS(451)  GROUND  = GND
  CJ76  VSS(450)  GROUND  = GND
  CJ78  VSS(449)  GROUND  = GND
  CJ80  DDR4_DQ(5)  BI  = M_E_DQ<5>
  CJ82  VSS(448)  GROUND  = GND
  CJ84  VSS(447)  GROUND  = GND
  CJ86  VSS(446)  GROUND  = GND
  CK1  PE2_TX_DP(4)  OUT  = P3E_CPU0_PE2_SS_TXP<4>
  CK3  PE2_TX_DP(5)  OUT  = P3E_CPU0_PE2_SS_TXP<5>
  CK5  VCCIO(22)  POWER  = PVCCIO_CPU0
  CK7  PE2_RX_DN(4)  IN  = P3E_CPU0_PE2_SS_RXN<4>
  CK9  DMI_RX_DN(0)  IN  = DMI_CPU0_PCH_RX_C_DN<0>
  CK11  VSS(445)  GROUND  = GND
  CK13  UPI2_TX_DP(13)  OUT  = TP_CPU0_UPI2_RSVD_DF17
  CK15  VSS(444)  GROUND  = GND
  CK17  UPI2_RX_DP(13)  IN  = GND
  CK19  RSVD(85)  BI  = TP_CPU0_RSVD_85
  CK21  VSS(443)  GROUND  = GND
  CK23  RSVD(84)  BI  = PVCCMCP_CPU0
  CK25  RSVD(83)  BI  = PVCCMCP_CPU0
  CK27  VSS(442)  GROUND  = GND
  CK29  UPI2_RBIAS(1)  IN  = A_CPU0_UPI2_RBIAS
  CK59  VCCIN(29)  POWER  = PVCCIN_CPU0
  CK61  VCCIN(28)  POWER  = PVCCIN_CPU0
  CK63  VSS(441)  GROUND  = GND
  CK65  VSS(440)  GROUND  = GND
  CK67  VSS(439)  GROUND  = GND
  CK69  VSS(438)  GROUND  = GND
  CK71  VSS(437)  GROUND  = GND
  CK73  VSS(436)  GROUND  = GND
  CK75  VSS(435)  GROUND  = GND
  CK77  RSVD(82)  BI  = TP_CPU0_RSVD_82
  CK79  DDR4_DQ(4)  BI  = M_E_DQ<4>
  CK81  DDR4_DQ(1)  BI  = M_E_DQ<1>
  CK83  VSS(434)  GROUND  = GND
  CK85  VSS(433)  GROUND  = GND
  CL2  PE2_TX_DN(5)  OUT  = P3E_CPU0_PE2_SS_TXN<5>
  CL4  DMI_TX_DP(1)  OUT  = DMI_CPU0_PCH_TX_DP<1>
  CL6  PE2_RX_DP(3)  IN  = P3E_CPU0_PE2_SS_RXP<3>
  CL8  VSS(432)  GROUND  = GND
  CL10  DMI_RX_DP(0)  IN  = DMI_CPU0_PCH_RX_C_DP<0>
  CL12  VCCIO(21)  POWER  = PVCCIO_CPU0
  CL14  VSS(431)  GROUND  = GND
  CL16  UPI2_RX_DN(12)  IN  = GND
  CL18  VSS(430)  GROUND  = GND
  CL20  VCCIO(11)  POWER  = PVCCIO_CPU0
  CL22  VSS(124)  GROUND  = GND
  CL24  RSVD(81)  BI  = PVCCMCP_CPU0
  CL26  RSVD(80)  BI  = PVCCMCP_CPU0
  CL28  UPI2_RBIAS(0)  IN  = A_CPU0_UPI2_RBIAS
  CL30  PE012_RBIAS(1)  BI  = A_CPU0_PE012_RBIAS
  CL58  VCCIN(27)  POWER  = PVCCIN_CPU0
  CL60  VCCIN(26)  POWER  = PVCCIN_CPU0
  CL62  VSS(427)  GROUND  = GND
  CL64  VSS(426)  GROUND  = GND
  CL66  VSS(425)  GROUND  = GND
  CL68  DDR5_ECC(3)  BI  = M_F_ECC<3>
  CL70  DDR5_DQS_DP(8)  BI  = M_F_DQS_DP<8>
  CL72  DDR5_ECC(5)  BI  = M_F_ECC<5>
  CL74  VSS(424)  GROUND  = GND
  CL76  VSS(423)  GROUND  = GND
  CL78  VSS(422)  GROUND  = GND
  CL80  VSS(421)  GROUND  = GND
  CL82  DDR4_DQS_DN(0)  BI  = M_E_DQS_DN<0>
  CL84  DDR3_DQ(4)  BI  = M_D_DQ<4>
  CL86  DDR3_DQ(5)  BI  = M_D_DQ<5>
  CM1  PE2_TX_DN(4)  OUT  = P3E_CPU0_PE2_SS_TXN<4>
  CM3  DMI_TX_DP(2)  OUT  = DMI_CPU0_PCH_TX_DP<2>
  CM5  VSS(418)  GROUND  = GND
  CM7  PE2_RX_DN(3)  IN  = P3E_CPU0_PE2_SS_RXN<3>
  CM9  PE2_RX_DP(1)  IN  = P3E_CPU0_PE2_SS_RXP<1>
  CM11  DMI_RX_DN(1)  IN  = DMI_CPU0_PCH_RX_C_DN<1>
  CM13  UPI2_TX_DN(13)  OUT  = TP_CPU0_UPI2_RSVD_DG18
  CM15  VCCIO(20)  POWER  = PVCCIO_CPU0
  CM19  VSS(420)  GROUND  = GND
  CM21  UPI2_RX_DP(11)  IN  = GND
  CM23  RSVD(79)  BI  = PVCCMCP_CPU0
  CM25  RSVD(78)  BI  = PVCCMCP_CPU0
  CM27  VSS(1168)  GROUND  = GND
  CM29  VSS(419)  GROUND  = GND
  CM31  VSS(417)  GROUND  = GND
  CM57  VCCIN(25)  POWER  = PVCCIN_CPU0
  CM59  VCCIN(24)  POWER  = PVCCIN_CPU0
  CM61  VSS(416)  GROUND  = GND
  CM63  VSS(415)  GROUND  = GND
  CM65  DDR5_DQS_DP(12)  BI  = M_F_DQS_DP<12>
  CM67  VSS(414)  GROUND  = GND
  CM69  DDR5_ECC(7)  BI  = M_F_ECC<7>
  CM71  DDR5_ECC(1)  BI  = M_F_ECC<1>
  CM73  VSS(413)  GROUND  = GND
  CM75  DDR5_DQ(5)  BI  = M_F_DQ<5>
  CM77  VSS(412)  GROUND  = GND
  CM79  DDR4_DQ(0)  BI  = M_E_DQ<0>
  CM81  DDR4_DQS_DP(0)  BI  = M_E_DQS_DP<0>
  CM83  VSS(411)  GROUND  = GND
  CM85  VSS(410)  GROUND  = GND
  CN2  VSS(409)  GROUND  = GND
  CN4  DMI_TX_DN(2)  OUT  = DMI_CPU0_PCH_TX_DN<2>
  CN6  VCCIO(19)  POWER  = PVCCIO_CPU0
  CN8  PE2_RX_DP(2)  IN  = P3E_CPU0_PE2_SS_RXP<2>
  CN10  DMI_RX_DP(1)  IN  = DMI_CPU0_PCH_RX_C_DP<1>
  CN12  VSS(408)  GROUND  = GND
  CN14  VSS(94)  GROUND  = GND
  CN18  UPI2_RX_DP(9)  IN  = GND
  CN20  UPI2_RX_DN(10)  IN  = GND
  CN22  RSVD(77)  BI  = TP_CPU0_KTI2_AMONV
  CN24  RSVD(76)  BI  = PVCCMCP_CPU0
  CN26  VSS(406)  GROUND  = GND
  CN28  RSVD(75)  BI  = PD_CPU0_MCP01_DMON
  CN30  PE012_RBIAS(0)  BI  = A_CPU0_PE012_RBIAS
  CN32  VSS(405)  GROUND  = GND
  CN56  VCCIN(23)  POWER  = PVCCIN_CPU0
  CN58  VCCIN(22)  POWER  = PVCCIN_CPU0
  CN60  VSS(404)  GROUND  = GND
  CN62  VSS(403)  GROUND  = GND
  CN64  DDR5_DQ(30)  BI  = M_F_DQ<30>
  CN66  DDR5_DQ(24)  BI  = M_F_DQ<24>
  CN68  VSS(402)  GROUND  = GND
  CN70  DDR5_DQS_DN(8)  BI  = M_F_DQS_DN<8>
  CN74  DDR5_DQ(4)  BI  = M_F_DQ<4>
  CN76  DDR5_DQ(1)  BI  = M_F_DQ<1>
  CN78  VSS(401)  GROUND  = GND
  CN80  DDR4_DQS_DN(9)  BI  = M_E_DQS_DN<9>
  CN82  DDR4_DQ(7)  BI  = M_E_DQ<7>
  CN84  DDR3_DQ(0)  BI  = M_D_DQ<0>
  CN86  DDR3_DQ(1)  BI  = M_D_DQ<1>
  CP1  VSS(400)  GROUND  = GND
  CP3  PE2_TX_DP(3)  OUT  = P3E_CPU0_PE2_SS_TXP<3>
  CP5  DMI_TX_DN(3)  OUT  = DMI_CPU0_PCH_TX_DN<3>
  CP7  PE2_RX_DN(2)  IN  = P3E_CPU0_PE2_SS_RXN<2>
  CP9  PE2_RX_DN(1)  IN  = P3E_CPU0_PE2_SS_RXN<1>
  CP11  DMI_RX_DP(2)  IN  = DMI_CPU0_PCH_RX_C_DP<2>
  CP13  VCCIO(12)  POWER  = PVCCIO_CPU0
  CP19  UPI2_RX_DP(10)  IN  = GND
  CP21  UPI2_RX_DN(11)  IN  = GND
  CP23  RSVD(74)  BI  = PVCCMCP_CPU0
  CP25  VSS(398)  GROUND  = GND
  CP27  BCLK1_DP  IN  = CLK_100M_CPU0_BCLK1_DP
  CP29  PE3_RBIAS(0)  IN  = A_CPU0_PE3_RBIAS
  CP31  RSVD(73)  BI  = TP_CPU0_RSVD_73
  CP33  VCCIN(21)  POWER  = PVCCIN_CPU0
  CP55  VCCIN(20)  POWER  = PVCCIN_CPU0
  CP57  VCCIN(19)  POWER  = PVCCIN_CPU0
  CP59  VSS(397)  GROUND  = GND
  CP61  DDR3_CAVREF  OUT  = M_D_CPU_VREF
  CP63  DDR5_DQ(26)  BI  = M_F_DQ<26>
  CP65  DDR5_DQS_DN(12)  BI  = M_F_DQS_DN<12>
  CP67  DDR5_DQ(28)  BI  = M_F_DQ<28>
  CP69  VSS(396)  GROUND  = GND
  CP73  VSS(395)  GROUND  = GND
  CP75  VSS(394)  GROUND  = GND
  CP77  DDR5_DQS_DN(0)  BI  = M_F_DQS_DN<0>
  CP79  DDR4_DQS_DP(9)  BI  = M_E_DQS_DP<9>
  CP81  VSS(393)  GROUND  = GND
  CP83  VSS(392)  GROUND  = GND
  CP85  DDR3_DQS_DP(9)  BI  = M_D_DQS_DP<9>
  CR2  PE2_TX_DP(2)  OUT  = P3E_CPU0_PE2_SS_TXP<2>
  CR4  DMI_TX_DP(3)  OUT  = DMI_CPU0_PCH_TX_DP<3>
  CR6  VSS(391)  GROUND  = GND
  CR8  PE2_RX_DP(0)  IN  = P3E_CPU0_PE2_SS_RXP<0>
  CR10  VSS(390)  GROUND  = GND
  CR12  DMI_RX_DN(2)  IN  = DMI_CPU0_PCH_RX_C_DN<2>
  CR14  UPI2_TX_DP(12)  OUT  = TP_CPU0_UPI2_RSVD_DE16
  CR18  UPI2_RX_DN(9)  IN  = GND
  CR20  UPI2_RX_DP(8)  IN  = GND
  CR22  VSS(389)  GROUND  = GND
  CR24  VSS(388)  GROUND  = GND
  CR26  BCLK1_DN  IN  = CLK_100M_CPU0_BCLK1_DN
  CR28  DDR345_DRAM_PWR_OK  IN  = PWRGD_CPU0_DRAMPWROK_DEF_G
